# BASEBOARD_FAB2 (Tioga Pass) — schematic netlist excerpt (pin names and nets, part order shuffled) for the footprints in the layout excerpt that follows; sources: Cadence DE-HDL packaged netlist, KiCad conversion of Wiwynn_Tioga_Pass_MB.brd

J6T1  SCONN288_H44441003  SCONN  pkg PIP  page 44
  \12v\(1)  = P12V_NVDIMM_ABC
  VSS(93)  = GND
  DQ(4)  = M_A_DQ<4>
  VSS(92)  = GND
  DQ(0)  = M_A_DQ<0>
  VSS(91)  = GND
  DQS9P  = M_A_DQS_DP<9>
  DQS9N  = M_A_DQS_DN<9>
  VSS(90)  = GND
  DQ(6)  = M_A_DQ<6>
  VSS(89)  = GND
  DQ(2)  = M_A_DQ<2>
  VSS(88)  = GND
  DQ(12)  = M_A_DQ<12>
  VSS(87)  = GND
  DQ(8)  = M_A_DQ<8>
  VSS(86)  = GND
  DQS10P  = M_A_DQS_DP<10>
  DQS10N  = M_A_DQS_DN<10>
  VSS(85)  = GND
  DQ(14)  = M_A_DQ<14>
  VSS(84)  = GND
  DQ(10)  = M_A_DQ<10>
  VSS(83)  = GND
  DQ(20)  = M_A_DQ<20>
  VSS(82)  = GND
  DQ(16)  = M_A_DQ<16>
  VSS(81)  = GND
  DQS11P  = M_A_DQS_DP<11>
  DQS11N  = M_A_DQS_DN<11>
  VSS(80)  = GND
  DQ(22)  = M_A_DQ<22>
  VSS(79)  = GND
  DQ(18)  = M_A_DQ<18>
  VSS(78)  = GND
  DQ(28)  = M_A_DQ<28>
  VSS(77)  = GND
  DQ(24)  = M_A_DQ<24>
  VSS(76)  = GND
  DQS12P  = M_A_DQS_DP<12>
  DQS12N  = M_A_DQS_DN<12>
  VSS(75)  = GND
  DQ(30)  = M_A_DQ<30>
  VSS(74)  = GND
  DQ(26)  = M_A_DQ<26>
  VSS(73)  = GND
  CB(4)  = M_A_ECC<4>
  VSS(72)  = GND
  CB(0)  = M_A_ECC<0>
  VSS(71)  = GND
  DQS17P  = M_A_DQS_DP<17>
  DQS17N  = M_A_DQS_DN<17>
  VSS(70)  = GND
  CB(6)  = M_A_ECC<6>
  VSS(69)  = GND
  CB(2)  = M_A_ECC<2>
  VSS(68)  = GND
  RESET_N  = M_ABC_RST_N
  VDD(25)  = PVDDQ_ABC
  CKE(0)  = M_A_CKE<2>
  VDD(24)  = PVDDQ_ABC
  ACT_N  = M_A_ACT_N
  BG(0)  = M_A_BG<0>
  VDD(23)  = PVDDQ_ABC
  A12  = M_A_MA<12>
  A9  = M_A_MA<9>
  VDD(22)  = PVDDQ_ABC
  A8  = M_A_MA<8>
  A6  = M_A_MA<6>
  VDD(21)  = PVDDQ_ABC
  A3  = M_A_MA<3>
  A1  = M_A_MA<1>
  VDD(20)  = PVDDQ_ABC
  CK0P  = M_A_CLK_DP<2>
  CK0N  = M_A_CLK_DN<2>
  VDD(19)  = PVDDQ_ABC
  VTT(1)  = PVTT_ABC
  EVENT_N  = FM_DIMM_EVENT_COD_N
  A0  = M_A_MA<0>
  VDD(18)  = PVDDQ_ABC
  BA(0)  = M_A_BA<0>
  A16_RAS_N  = M_A_MA<16>
  VDD(17)  = PVDDQ_ABC
  S0_N  = M_A_CS_N<4>
  VDD(16)  = PVDDQ_ABC
  A15_CAS_N  = M_A_MA<15>
  ODT(0)  = M_A_ODT<2>
  VDD(15)  = PVDDQ_ABC
  S1_N  = M_A_CS_N<5>
  VDD(14)  = PVDDQ_ABC
  ODT(1)  = M_A_ODT<3>
  VDD(13)  = PVDDQ_ABC
  S2_N_C(0)  = M_A_CS_N<6>
  VSS(67)  = GND
  DQ(36)  = M_A_DQ<36>
  VSS(66)  = GND
  DQ(32)  = M_A_DQ<32>
  VSS(65)  = GND
  DQS13P  = M_A_DQS_DP<13>
  DQS13N  = M_A_DQS_DN<13>
  VSS(64)  = GND
  DQ(38)  = M_A_DQ<38>
  VSS(63)  = GND
  DQ(34)  = M_A_DQ<34>
  VSS(62)  = GND
  DQ(44)  = M_A_DQ<44>
  VSS(61)  = GND
  DQ(40)  = M_A_DQ<40>
  VSS(60)  = GND
  DQS14P  = M_A_DQS_DP<14>
  DQS14N  = M_A_DQS_DN<14>
  VSS(59)  = GND
  DQ(46)  = M_A_DQ<46>
  VSS(58)  = GND
  DQ(42)  = M_A_DQ<42>
  VSS(57)  = GND
  DQ(52)  = M_A_DQ<52>
  VSS(56)  = GND
  DQ(48)  = M_A_DQ<48>
  VSS(55)  = GND
  DQS15P  = M_A_DQS_DP<15>
  DQS15N  = M_A_DQS_DN<15>
  VSS(54)  = GND
  DQ(54)  = M_A_DQ<54>
  VSS(53)  = GND
  DQ(50)  = M_A_DQ<50>
  VSS(52)  = GND
  DQ(60)  = M_A_DQ<60>
  VSS(51)  = GND
  DQ(56)  = M_A_DQ<56>
  VSS(50)  = GND
  DQS16P  = M_A_DQS_DP<16>
  DQS16N  = M_A_DQS_DN<16>
  VSS(49)  = GND
  DQ(62)  = M_A_DQ<62>
  VSS(48)  = GND
  DQ(58)  = M_A_DQ<58>
  VSS(47)  = GND
  SA(0)  = PVPP_ABC
  SA(1)  = GND
  SCL  = SMB_DDR_ABC_VPP_SCL
  VPP(4)  = PVPP_ABC
  VPP(3)  = PVPP_ABC
  RFU(2)  = TP_CH_A_DIMM_A1_RFU_2
  \12v\(0)  = P12V_NVDIMM_ABC
  VREFCA  = M_A_VREF
  VSS(46)  = GND
  DQ(5)  = M_A_DQ<5>
  VSS(45)  = GND
  DQ(1)  = M_A_DQ<1>
  VSS(44)  = GND
  DQS0N  = M_A_DQS_DN<0>
  DQS0P  = M_A_DQS_DP<0>
  VSS(43)  = GND
  DQ(7)  = M_A_DQ<7>
  VSS(42)  = GND
  DQ(3)  = M_A_DQ<3>
  VSS(41)  = GND
  DQ(13)  = M_A_DQ<13>
  VSS(40)  = GND
  DQ(9)  = M_A_DQ<9>
  VSS(39)  = GND
  DQS1N  = M_A_DQS_DN<1>
  DQS1P  = M_A_DQS_DP<1>
  VSS(38)  = GND
  DQ(15)  = M_A_DQ<15>
  VSS(37)  = GND
  DQ(11)  = M_A_DQ<11>
  VSS(36)  = GND
  DQ(21)  = M_A_DQ<21>
  VSS(35)  = GND
  DQ(17)  = M_A_DQ<17>
  VSS(34)  = GND
  DQS2N  = M_A_DQS_DN<2>
  DQS2P  = M_A_DQS_DP<2>
  VSS(33)  = GND
  DQ(23)  = M_A_DQ<23>
  VSS(32)  = GND
  DQ(19)  = M_A_DQ<19>
  VSS(31)  = GND
  DQ(29)  = M_A_DQ<29>
  VSS(30)  = GND
  DQ(25)  = M_A_DQ<25>
  VSS(29)  = GND
  DQS3N  = M_A_DQS_DN<3>
  DQS3P  = M_A_DQS_DP<3>
  VSS(28)  = GND
  DQ(31)  = M_A_DQ<31>
  VSS(27)  = GND
  DQ(27)  = M_A_DQ<27>
  VSS(26)  = GND
  CB(5)  = M_A_ECC<5>
  VSS(25)  = GND
  CB(1)  = M_A_ECC<1>
  VSS(24)  = GND
  DQS8N  = M_A_DQS_DN<8>
  DQS8P  = M_A_DQS_DP<8>
  VSS(23)  = GND
  CB(7)  = M_A_ECC<7>
  VSS(22)  = GND
  CB(3)  = M_A_ECC<3>
  VSS(21)  = GND
  CKE(1)  = M_A_CKE<3>
  VDD(12)  = PVDDQ_ABC
  RFU(0)  = TP_CH_A_DIMM_A1_RFU_0
  VDD(11)  = PVDDQ_ABC
  BG(1)  = M_A_BG<1>
  ALERT_N  = M_A_ALERT_N
  VDD(10)  = PVDDQ_ABC
  A11  = M_A_MA<11>
  A7  = M_A_MA<7>
  VDD(9)  = PVDDQ_ABC
  A5  = M_A_MA<5>
  A4  = M_A_MA<4>
  VDD(8)  = PVDDQ_ABC
  A2  = M_A_MA<2>
  VDD(7)  = PVDDQ_ABC
  CK1P  = M_A_CLK_DP<3>
  CK1N  = M_A_CLK_DN<3>
  VDD(6)  = PVDDQ_ABC
  VTT(0)  = PVTT_ABC
  PAR  = M_A_PAR
  VDD(5)  = PVDDQ_ABC
  BA(1)  = M_A_BA<1>
  A10  = M_A_MA<10>
  VDD(4)  = PVDDQ_ABC
  RFU(1)  = TP_CH_A_DIMM_A1_RFU_1
  A14_WE_N  = M_A_MA<14>
  VDD(3)  = PVDDQ_ABC
  SAVE_N_NC  = FM_ADR_COMPLETE_ABC_N
  VDD(2)  = PVDDQ_ABC
  A13  = M_A_MA<13>
  VDD(1)  = PVDDQ_ABC
  A17  = M_A_MA<17>
  C(2)  = M_A_C<2>
  VDD(0)  = PVDDQ_ABC
  S3_N_C(1)  = M_A_CS_N<7>
  SA(2)  = GND
  VSS(20)  = GND
  DQ(37)  = M_A_DQ<37>
  VSS(19)  = GND
  DQ(33)  = M_A_DQ<33>
  VSS(18)  = GND
  DQS4N  = M_A_DQS_DN<4>
  DQS4P  = M_A_DQS_DP<4>
  VSS(17)  = GND
  DQ(39)  = M_A_DQ<39>
  VSS(16)  = GND
  DQ(35)  = M_A_DQ<35>
  VSS(15)  = GND
  DQ(45)  = M_A_DQ<45>
  VSS(14)  = GND
  DQ(41)  = M_A_DQ<41>
  VSS(13)  = GND
  DQS5N  = M_A_DQS_DN<5>
  DQS5P  = M_A_DQS_DP<5>
  VSS(12)  = GND
  DQ(47)  = M_A_DQ<47>
  VSS(11)  = GND
  DQ(43)  = M_A_DQ<43>
  VSS(10)  = GND
  DQ(53)  = M_A_DQ<53>
  VSS(9)  = GND
  DQ(49)  = M_A_DQ<49>
  VSS(8)  = GND
  DQS6N  = M_A_DQS_DN<6>
  DQS6P  = M_A_DQS_DP<6>
  VSS(7)  = GND
  DQ(55)  = M_A_DQ<55>
  VSS(6)  = GND
  DQ(51)  = M_A_DQ<51>
  VSS(5)  = GND
  DQ(61)  = M_A_DQ<61>
  VSS(4)  = GND
  DQ(57)  = M_A_DQ<57>
  VSS(3)  = GND
  DQS7N  = M_A_DQS_DN<7>
  DQS7P  = M_A_DQS_DP<7>
  VSS(2)  = GND
  DQ(63)  = M_A_DQ<63>
  VSS(1)  = GND
  DQ(59)  = M_A_DQ<59>
  VSS(0)  = GND
  VDDSPD  = PVPP_ABC
  SDA  = SMB_DDR_ABC_VPP_SDA
  VPP(1)  = PVPP_ABC
  VPP(0)  = PVPP_ABC
  VPP(2)  = PVPP_ABC

(kicad_pcb
	(version 20260206)
	(generator "pcbnew")
	(generator_version "10.0")
	(general
		(thickness 1.6)
		(legacy_teardrops no)
	)
	(paper "A4")
	(title_block
		(title "Wiwynn_Tioga_Pass_MB.brd")
		(comment 1 "Tioga Pass / footprint 3283 of 4770 (J6T1), pads 152-201 of 291")
	)
	(layers
		(0 "F.Cu" signal "TOP")
		(4 "In1.Cu" signal "L2GND")
		(6 "In2.Cu" signal "L3")
		(8 "In3.Cu" signal "L4GND")
		(10 "In4.Cu" signal "L5")
		(12 "In5.Cu" signal "L6GND")
		(14 "In6.Cu" signal "L7VCC")
		(16 "In7.Cu" signal "L8VCC")
		(18 "In8.Cu" signal "L9GND")
		(20 "In9.Cu" signal "L10")
		(22 "In10.Cu" signal "L11GND")
		(24 "In11.Cu" signal "L12")
		(26 "In12.Cu" signal "L13GND")
		(2 "B.Cu" signal "BOTTOM")
		(9 "F.Adhes" user "F.Adhesive")
		(11 "B.Adhes" user "B.Adhesive")
		(13 "F.Paste" user "Package Geometry/Pastemask Top")
		(15 "B.Paste" user "Package Geometry/Pastemask Bottom")
		(5 "F.SilkS" user "Ref Des/Silkscreen Top")
		(7 "B.SilkS" user "Ref Des/Silkscreen Bottom")
		(1 "F.Mask" user "Board Geometry/Soldermask Top")
		(3 "B.Mask" user "Board Geometry/Soldermask Bottom")
		(17 "Dwgs.User" user "User.Drawings")
		(19 "Cmts.User" user "User.Comments")
		(21 "Eco1.User" user "User.Eco1")
		(23 "Eco2.User" user "User.Eco2")
		(25 "Edge.Cuts" user "Board Geometry/Outline")
		(27 "Margin" user)
		(31 "F.CrtYd" user "Package Geometry/Place Bound Top")
		(29 "B.CrtYd" user "Package Geometry/Place Bound Bottom")
		(35 "F.Fab" user "Ref Des/Assembly Top")
		(33 "B.Fab" user "Ref Des/Assembly Bottom")
	)
	(footprint ""
		(layer "B.Cu")
		(at 194.700398 -24.824182 90)
		(property "Reference" "J6T1"
			(at 2.200148 39.23411 0)
			(unlocked yes)
			(layer "B.SilkS")
			(effects
				(font
					(size 0.7874 0.5842)
					(thickness 0.1524)
				)
				(justify left mirror)
			)
		)
		(property "Value" ""
			(at 0 0 90)
			(layer "B.Fab")
			(effects
				(font
					(size 1.27 1.27)
				)
				(justify mirror)
			)
		)
		(duplicate_pad_numbers_are_jumpers no)
		(pad "149" smd rect
			(at -4.59994 3.400044 270)
			(size 1.8034 0.508)
			(layers "B.Cu" "B.Mask" "B.Paste")
			(net "GND")
		)
		(pad "150" smd rect
			(at -4.59994 4.249928 270)
			(size 1.8034 0.508)
			(layers "B.Cu" "B.Mask" "B.Paste")
			(net "M_A_DQ<1>")
		)
		(pad "151" smd rect
			(at -4.59994 5.100066 270)
			(size 1.8034 0.508)
			(layers "B.Cu" "B.Mask" "B.Paste")
			(net "GND")
		)
		(pad "152" smd rect
			(at -4.59994 5.94995 270)
			(size 1.8034 0.508)
			(layers "B.Cu" "B.Mask" "B.Paste")
			(net "M_A_DQS_DN<0>")
		)
		(pad "153" smd rect
			(at -4.59994 6.800088 270)
			(size 1.8034 0.508)
			(layers "B.Cu" "B.Mask" "B.Paste")
			(net "M_A_DQS_DP<0>")
		)
		(pad "154" smd rect
			(at -4.59994 7.649972 270)
			(size 1.8034 0.508)
			(layers "B.Cu" "B.Mask" "B.Paste")
			(net "GND")
		)
		(pad "155" smd rect
			(at -4.59994 8.50011 270)
			(size 1.8034 0.508)
			(layers "B.Cu" "B.Mask" "B.Paste")
			(net "M_A_DQ<7>")
		)
		(pad "156" smd rect
			(at -4.59994 9.349994 270)
			(size 1.8034 0.508)
			(layers "B.Cu" "B.Mask" "B.Paste")
			(net "GND")
		)
		(pad "157" smd rect
			(at -4.59994 10.199878 270)
			(size 1.8034 0.508)
			(layers "B.Cu" "B.Mask" "B.Paste")
			(net "M_A_DQ<3>")
		)
		(pad "158" smd rect
			(at -4.59994 11.050016 270)
			(size 1.8034 0.508)
			(layers "B.Cu" "B.Mask" "B.Paste")
			(net "GND")
		)
		(pad "159" smd rect
			(at -4.59994 11.8999 270)
			(size 1.8034 0.508)
			(layers "B.Cu" "B.Mask" "B.Paste")
			(net "M_A_DQ<13>")
		)
		(pad "160" smd rect
			(at -4.59994 12.750038 270)
			(size 1.8034 0.508)
			(layers "B.Cu" "B.Mask" "B.Paste")
			(net "GND")
		)
		(pad "161" smd rect
			(at -4.59994 13.599922 270)
			(size 1.8034 0.508)
			(layers "B.Cu" "B.Mask" "B.Paste")
			(net "M_A_DQ<9>")
		)
		(pad "162" smd rect
			(at -4.59994 14.45006 270)
			(size 1.8034 0.508)
			(layers "B.Cu" "B.Mask" "B.Paste")
			(net "GND")
		)
		(pad "163" smd rect
			(at -4.59994 15.299944 270)
			(size 1.8034 0.508)
			(layers "B.Cu" "B.Mask" "B.Paste")
			(net "M_A_DQS_DN<1>")
		)
		(pad "164" smd rect
			(at -4.59994 16.150082 270)
			(size 1.8034 0.508)
			(layers "B.Cu" "B.Mask" "B.Paste")
			(net "M_A_DQS_DP<1>")
		)
		(pad "165" smd rect
			(at -4.59994 16.999966 270)
			(size 1.8034 0.508)
			(layers "B.Cu" "B.Mask" "B.Paste")
			(net "GND")
		)
		(pad "166" smd rect
			(at -4.59994 17.850104 270)
			(size 1.8034 0.508)
			(layers "B.Cu" "B.Mask" "B.Paste")
			(net "M_A_DQ<15>")
		)
		(pad "167" smd rect
			(at -4.59994 18.699988 270)
			(size 1.8034 0.508)
			(layers "B.Cu" "B.Mask" "B.Paste")
			(net "GND")
		)
		(pad "168" smd rect
			(at -4.59994 19.550126 270)
			(size 1.8034 0.508)
			(layers "B.Cu" "B.Mask" "B.Paste")
			(net "M_A_DQ<11>")
		)
		(pad "169" smd rect
			(at -4.59994 20.40001 270)
			(size 1.8034 0.508)
			(layers "B.Cu" "B.Mask" "B.Paste")
			(net "GND")
		)
		(pad "170" smd rect
			(at -4.59994 21.249894 270)
			(size 1.8034 0.508)
			(layers "B.Cu" "B.Mask" "B.Paste")
			(net "M_A_DQ<21>")
		)
		(pad "171" smd rect
			(at -4.59994 22.100032 270)
			(size 1.8034 0.508)
			(layers "B.Cu" "B.Mask" "B.Paste")
			(net "GND")
		)
		(pad "172" smd rect
			(at -4.59994 22.949916 270)
			(size 1.8034 0.508)
			(layers "B.Cu" "B.Mask" "B.Paste")
			(net "M_A_DQ<17>")
		)
		(pad "173" smd rect
			(at -4.59994 23.800054 270)
			(size 1.8034 0.508)
			(layers "B.Cu" "B.Mask" "B.Paste")
			(net "GND")
		)
		(pad "174" smd rect
			(at -4.59994 24.649938 270)
			(size 1.8034 0.508)
			(layers "B.Cu" "B.Mask" "B.Paste")
			(net "M_A_DQS_DN<2>")
		)
		(pad "175" smd rect
			(at -4.59994 25.500076 270)
			(size 1.8034 0.508)
			(layers "B.Cu" "B.Mask" "B.Paste")
			(net "M_A_DQS_DP<2>")
		)
		(pad "176" smd rect
			(at -4.59994 26.34996 270)
			(size 1.8034 0.508)
			(layers "B.Cu" "B.Mask" "B.Paste")
			(net "GND")
		)
		(pad "177" smd rect
			(at -4.59994 27.200098 270)
			(size 1.8034 0.508)
			(layers "B.Cu" "B.Mask" "B.Paste")
			(net "M_A_DQ<23>")
		)
		(pad "178" smd rect
			(at -4.59994 28.049982 270)
			(size 1.8034 0.508)
			(layers "B.Cu" "B.Mask" "B.Paste")
			(net "GND")
		)
		(pad "179" smd rect
			(at -4.59994 28.90012 270)
			(size 1.8034 0.508)
			(layers "B.Cu" "B.Mask" "B.Paste")
			(net "M_A_DQ<19>")
		)
		(pad "180" smd rect
			(at -4.59994 29.750004 270)
			(size 1.8034 0.508)
			(layers "B.Cu" "B.Mask" "B.Paste")
			(net "GND")
		)
		(pad "181" smd rect
			(at -4.59994 30.599888 270)
			(size 1.8034 0.508)
			(layers "B.Cu" "B.Mask" "B.Paste")
			(net "M_A_DQ<29>")
		)
		(pad "182" smd rect
			(at -4.59994 31.450026 270)
			(size 1.8034 0.508)
			(layers "B.Cu" "B.Mask" "B.Paste")
			(net "GND")
		)
		(pad "183" smd rect
			(at -4.59994 32.29991 270)
			(size 1.8034 0.508)
			(layers "B.Cu" "B.Mask" "B.Paste")
			(net "M_A_DQ<25>")
		)
		(pad "184" smd rect
			(at -4.59994 33.150048 270)
			(size 1.8034 0.508)
			(layers "B.Cu" "B.Mask" "B.Paste")
			(net "GND")
		)
		(pad "185" smd rect
			(at -4.59994 33.999932 270)
			(size 1.8034 0.508)
			(layers "B.Cu" "B.Mask" "B.Paste")
			(net "M_A_DQS_DN<3>")
		)
		(pad "186" smd rect
			(at -4.59994 34.85007 270)
			(size 1.8034 0.508)
			(layers "B.Cu" "B.Mask" "B.Paste")
			(net "M_A_DQS_DP<3>")
		)
		(pad "187" smd rect
			(at -4.59994 35.699954 270)
			(size 1.8034 0.508)
			(layers "B.Cu" "B.Mask" "B.Paste")
			(net "GND")
		)
		(pad "188" smd rect
			(at -4.59994 36.550092 270)
			(size 1.8034 0.508)
			(layers "B.Cu" "B.Mask" "B.Paste")
			(net "M_A_DQ<31>")
		)
		(pad "189" smd rect
			(at -4.59994 37.399976 270)
			(size 1.8034 0.508)
			(layers "B.Cu" "B.Mask" "B.Paste")
			(net "GND")
		)
		(pad "190" smd rect
			(at -4.59994 38.250114 270)
			(size 1.8034 0.508)
			(layers "B.Cu" "B.Mask" "B.Paste")
			(net "M_A_DQ<27>")
		)
		(pad "191" smd rect
			(at -4.59994 39.099998 270)
			(size 1.8034 0.508)
			(layers "B.Cu" "B.Mask" "B.Paste")
			(net "GND")
		)
		(pad "192" smd rect
			(at -4.59994 39.949882 270)
			(size 1.8034 0.508)
			(layers "B.Cu" "B.Mask" "B.Paste")
			(net "M_A_ECC<5>")
		)
		(pad "193" smd rect
			(at -4.59994 40.80002 270)
			(size 1.8034 0.508)
			(layers "B.Cu" "B.Mask" "B.Paste")
			(net "GND")
		)
		(pad "194" smd rect
			(at -4.59994 41.649904 270)
			(size 1.8034 0.508)
			(layers "B.Cu" "B.Mask" "B.Paste")
			(net "M_A_ECC<1>")
		)
		(pad "195" smd rect
			(at -4.59994 42.500042 270)
			(size 1.8034 0.508)
			(layers "B.Cu" "B.Mask" "B.Paste")
			(net "GND")
		)
		(pad "196" smd rect
			(at -4.59994 43.349926 270)
			(size 1.8034 0.508)
			(layers "B.Cu" "B.Mask" "B.Paste")
			(net "M_A_DQS_DN<8>")
		)
		(pad "197" smd rect
			(at -4.59994 44.200064 270)
			(size 1.8034 0.508)
			(layers "B.Cu" "B.Mask" "B.Paste")
			(net "M_A_DQS_DP<8>")
		)
		(pad "198" smd rect
			(at -4.59994 45.049948 270)
			(size 1.8034 0.508)
			(layers "B.Cu" "B.Mask" "B.Paste")
			(net "GND")
		)
	)
)
